(kicad_pcb
	(version 20260206)
	(generator "pcbnew")
	(generator_version "10.0")
	(general
		(thickness 1.6)
		(legacy_teardrops no)
	)
	(paper "A4")
	(title_block
		(title "01162023_DA0F0TEBIF0_F0T_Expander_BD_F_brd_V02_OCP.brd")
		(comment 1 "Grand Teton / footprints 918-923 of 9728")
	)
	(layers
		(0 "F.Cu" signal "TOP")
		(4 "In1.Cu" signal "GND")
		(6 "In2.Cu" signal "VCC")
		(8 "In3.Cu" signal "VCC1")
		(10 "In4.Cu" signal "GND1")
		(12 "In5.Cu" signal "IN1")
		(14 "In6.Cu" signal "GND2")
		(16 "In7.Cu" signal "IN2")
		(18 "In8.Cu" signal "GND3")
		(20 "In9.Cu" signal "IN3")
		(22 "In10.Cu" signal "GND4")
		(24 "In11.Cu" signal "IN4")
		(26 "In12.Cu" signal "GND5")
		(28 "In13.Cu" signal "IN5")
		(30 "In14.Cu" signal "GND6")
		(32 "In15.Cu" signal "IN6")
		(34 "In16.Cu" signal "GND7")
		(2 "B.Cu" signal "BOTTOM")
		(9 "F.Adhes" user "F.Adhesive")
		(11 "B.Adhes" user "B.Adhesive")
		(13 "F.Paste" user "Package Geometry/Pastemask Top")
		(15 "B.Paste" user "Package Geometry/Pastemask Bottom")
		(5 "F.SilkS" user "Ref Des/Silkscreen Top")
		(7 "B.SilkS" user "Ref Des/Silkscreen Bottom")
		(1 "F.Mask" user "Board Geometry/Soldermask Top")
		(3 "B.Mask" user "Board Geometry/Soldermask Bottom")
		(17 "Dwgs.User" user "User.Drawings")
		(19 "Cmts.User" user "User.Comments")
		(21 "Eco1.User" user "User.Eco1")
		(23 "Eco2.User" user "User.Eco2")
		(25 "Edge.Cuts" user "Board Geometry/Outline")
		(27 "Margin" user)
		(31 "F.CrtYd" user "Package Geometry/Place Bound Top")
		(29 "B.CrtYd" user "Package Geometry/Place Bound Bottom")
		(35 "F.Fab" user "Ref Des/Assembly Top")
		(33 "B.Fab" user "Ref Des/Assembly Bottom")
	)
	(footprint ""
		(layer "F.Cu")
		(at 374.674384 -252.356874 -90)
		(property "Reference" "R1427"
			(at 0 0 270)
			(layer "F.SilkS")
			(hide yes)
			(effects
				(font
					(size 1.27 1.27)
				)
			)
		)
		(property "Value" ""
			(at 0 0 270)
			(layer "F.Fab")
			(effects
				(font
					(size 1.27 1.27)
				)
			)
		)
		(duplicate_pad_numbers_are_jumpers no)
		(fp_line
			(start -0.7874 0.4064)
			(end -0.7874 -0.4064)
			(stroke
				(width 0.1524)
				(type default)
			)
			(layer "F.SilkS")
		)
		(fp_line
			(start 0.7874 0.4064)
			(end -0.7874 0.4064)
			(stroke
				(width 0.1524)
				(type default)
			)
			(layer "F.SilkS")
		)
		(fp_line
			(start -0.7874 -0.4064)
			(end 0.7874 -0.4064)
			(stroke
				(width 0.1524)
				(type default)
			)
			(layer "F.SilkS")
		)
		(fp_line
			(start 0.7874 -0.4064)
			(end 0.7874 0.4064)
			(stroke
				(width 0.1524)
				(type default)
			)
			(layer "F.SilkS")
		)
		(fp_line
			(start -0.67945 0.3048)
			(end -0.67945 -0.305054)
			(stroke
				(width 0.1)
				(type default)
			)
			(layer "F.Fab")
		)
		(fp_line
			(start -0.12065 0.3048)
			(end -0.67945 0.3048)
			(stroke
				(width 0.1)
				(type default)
			)
			(layer "F.Fab")
		)
		(fp_line
			(start 0.120396 0.3048)
			(end 0.120396 0.2794)
			(stroke
				(width 0.1)
				(type default)
			)
			(layer "F.Fab")
		)
		(fp_line
			(start 0.67945 0.3048)
			(end 0.120396 0.3048)
			(stroke
				(width 0.1)
				(type default)
			)
			(layer "F.Fab")
		)
		(fp_line
			(start -0.12065 0.2794)
			(end -0.12065 0.3048)
			(stroke
				(width 0.1)
				(type default)
			)
			(layer "F.Fab")
		)
		(fp_line
			(start 0.120396 0.2794)
			(end -0.12065 0.2794)
			(stroke
				(width 0.1)
				(type default)
			)
			(layer "F.Fab")
		)
		(fp_line
			(start -0.12065 -0.2794)
			(end 0.12065 -0.2794)
			(stroke
				(width 0.1)
				(type default)
			)
			(layer "F.Fab")
		)
		(fp_line
			(start 0.12065 -0.2794)
			(end 0.12065 -0.3048)
			(stroke
				(width 0.1)
				(type default)
			)
			(layer "F.Fab")
		)
		(fp_line
			(start 0.12065 -0.3048)
			(end 0.67945 -0.3048)
			(stroke
				(width 0.1)
				(type default)
			)
			(layer "F.Fab")
		)
		(fp_line
			(start 0.67945 -0.3048)
			(end 0.67945 0.3048)
			(stroke
				(width 0.1)
				(type default)
			)
			(layer "F.Fab")
		)
		(fp_line
			(start -0.67945 -0.305054)
			(end -0.12065 -0.305054)
			(stroke
				(width 0.1)
				(type default)
			)
			(layer "F.Fab")
		)
		(fp_line
			(start -0.12065 -0.305054)
			(end -0.12065 -0.2794)
			(stroke
				(width 0.1)
				(type default)
			)
			(layer "F.Fab")
		)
		(pad "1" smd circle
			(at -0.40005 0 270)
			(size 0 0)
			(layers "F.Cu" "F.Mask" "F.Paste")
			(net "GND")
		)
		(pad "2" smd circle
			(at 0.40005 0 270)
			(size 0 0)
			(layers "F.Cu" "F.Mask" "F.Paste")
			(net "PEX3_MODE_SEL2")
		)
	)
	(footprint ""
		(layer "F.Cu")
		(at 214.775034 -56.977534 180)
		(property "Reference" "PC388"
			(at 0 0 180)
			(layer "F.SilkS")
			(hide yes)
			(effects
				(font
					(size 1.27 1.27)
				)
			)
		)
		(property "Value" ""
			(at 0 0 180)
			(layer "F.Fab")
			(effects
				(font
					(size 1.27 1.27)
				)
			)
		)
		(duplicate_pad_numbers_are_jumpers no)
		(fp_line
			(start 0.7874 0.4064)
			(end -0.7874 0.4064)
			(stroke
				(width 0.1524)
				(type default)
			)
			(layer "F.SilkS")
		)
		(fp_line
			(start 0.7874 -0.4064)
			(end 0.7874 0.4064)
			(stroke
				(width 0.1524)
				(type default)
			)
			(layer "F.SilkS")
		)
		(fp_line
			(start -0.7874 0.4064)
			(end -0.7874 -0.4064)
			(stroke
				(width 0.1524)
				(type default)
			)
			(layer "F.SilkS")
		)
		(fp_line
			(start -0.7874 -0.4064)
			(end 0.7874 -0.4064)
			(stroke
				(width 0.1524)
				(type default)
			)
			(layer "F.SilkS")
		)
		(fp_line
			(start 0.67945 0.3048)
			(end 0.120396 0.3048)
			(stroke
				(width 0.1)
				(type default)
			)
			(layer "F.Fab")
		)
		(fp_line
			(start 0.67945 -0.3048)
			(end 0.67945 0.3048)
			(stroke
				(width 0.1)
				(type default)
			)
			(layer "F.Fab")
		)
		(fp_line
			(start 0.12065 -0.2794)
			(end 0.12065 -0.3048)
			(stroke
				(width 0.1)
				(type default)
			)
			(layer "F.Fab")
		)
		(fp_line
			(start 0.12065 -0.3048)
			(end 0.67945 -0.3048)
			(stroke
				(width 0.1)
				(type default)
			)
			(layer "F.Fab")
		)
		(fp_line
			(start 0.120396 0.3048)
			(end 0.120396 0.2794)
			(stroke
				(width 0.1)
				(type default)
			)
			(layer "F.Fab")
		)
		(fp_line
			(start 0.120396 0.2794)
			(end -0.12065 0.2794)
			(stroke
				(width 0.1)
				(type default)
			)
			(layer "F.Fab")
		)
		(fp_line
			(start -0.12065 0.3048)
			(end -0.67945 0.3048)
			(stroke
				(width 0.1)
				(type default)
			)
			(layer "F.Fab")
		)
		(fp_line
			(start -0.12065 0.2794)
			(end -0.12065 0.3048)
			(stroke
				(width 0.1)
				(type default)
			)
			(layer "F.Fab")
		)
		(fp_line
			(start -0.12065 -0.2794)
			(end 0.12065 -0.2794)
			(stroke
				(width 0.1)
				(type default)
			)
			(layer "F.Fab")
		)
		(fp_line
			(start -0.12065 -0.305054)
			(end -0.12065 -0.2794)
			(stroke
				(width 0.1)
				(type default)
			)
			(layer "F.Fab")
		)
		(fp_line
			(start -0.67945 0.3048)
			(end -0.67945 -0.305054)
			(stroke
				(width 0.1)
				(type default)
			)
			(layer "F.Fab")
		)
		(fp_line
			(start -0.67945 -0.305054)
			(end -0.12065 -0.305054)
			(stroke
				(width 0.1)
				(type default)
			)
			(layer "F.Fab")
		)
		(pad "1" smd circle
			(at -0.40005 0 180)
			(size 0 0)
			(layers "F.Cu" "F.Mask" "F.Paste")
			(net "P12V_AUX")
		)
		(pad "2" smd circle
			(at 0.40005 0 180)
			(size 0 0)
			(layers "F.Cu" "F.Mask" "F.Paste")
			(net "GND")
		)
	)
	(footprint ""
		(layer "F.Cu")
		(at 338.963 -234.061 90)
		(property "Reference" "R3586"
			(at 0 0 90)
			(layer "F.SilkS")
			(hide yes)
			(effects
				(font
					(size 1.27 1.27)
				)
			)
		)
		(property "Value" ""
			(at 0 0 90)
			(layer "F.Fab")
			(effects
				(font
					(size 1.27 1.27)
				)
			)
		)
		(duplicate_pad_numbers_are_jumpers no)
		(fp_line
			(start 0.7874 -0.4064)
			(end 0.7874 0.4064)
			(stroke
				(width 0.1524)
				(type default)
			)
			(layer "F.SilkS")
		)
		(fp_line
			(start -0.7874 -0.4064)
			(end 0.7874 -0.4064)
			(stroke
				(width 0.1524)
				(type default)
			)
			(layer "F.SilkS")
		)
		(fp_line
			(start 0.7874 0.4064)
			(end -0.7874 0.4064)
			(stroke
				(width 0.1524)
				(type default)
			)
			(layer "F.SilkS")
		)
		(fp_line
			(start -0.7874 0.4064)
			(end -0.7874 -0.4064)
			(stroke
				(width 0.1524)
				(type default)
			)
			(layer "F.SilkS")
		)
		(fp_line
			(start -0.12065 -0.305054)
			(end -0.12065 -0.2794)
			(stroke
				(width 0.1)
				(type default)
			)
			(layer "F.Fab")
		)
		(fp_line
			(start -0.67945 -0.305054)
			(end -0.12065 -0.305054)
			(stroke
				(width 0.1)
				(type default)
			)
			(layer "F.Fab")
		)
		(fp_line
			(start 0.67945 -0.3048)
			(end 0.67945 0.3048)
			(stroke
				(width 0.1)
				(type default)
			)
			(layer "F.Fab")
		)
		(fp_line
			(start 0.12065 -0.3048)
			(end 0.67945 -0.3048)
			(stroke
				(width 0.1)
				(type default)
			)
			(layer "F.Fab")
		)
		(fp_line
			(start 0.12065 -0.2794)
			(end 0.12065 -0.3048)
			(stroke
				(width 0.1)
				(type default)
			)
			(layer "F.Fab")
		)
		(fp_line
			(start -0.12065 -0.2794)
			(end 0.12065 -0.2794)
			(stroke
				(width 0.1)
				(type default)
			)
			(layer "F.Fab")
		)
		(fp_line
			(start 0.120396 0.2794)
			(end -0.12065 0.2794)
			(stroke
				(width 0.1)
				(type default)
			)
			(layer "F.Fab")
		)
		(fp_line
			(start -0.12065 0.2794)
			(end -0.12065 0.3048)
			(stroke
				(width 0.1)
				(type default)
			)
			(layer "F.Fab")
		)
		(fp_line
			(start 0.67945 0.3048)
			(end 0.120396 0.3048)
			(stroke
				(width 0.1)
				(type default)
			)
			(layer "F.Fab")
		)
		(fp_line
			(start 0.120396 0.3048)
			(end 0.120396 0.2794)
			(stroke
				(width 0.1)
				(type default)
			)
			(layer "F.Fab")
		)
		(fp_line
			(start -0.12065 0.3048)
			(end -0.67945 0.3048)
			(stroke
				(width 0.1)
				(type default)
			)
			(layer "F.Fab")
		)
		(fp_line
			(start -0.67945 0.3048)
			(end -0.67945 -0.305054)
			(stroke
				(width 0.1)
				(type default)
			)
			(layer "F.Fab")
		)
		(pad "1" smd circle
			(at -0.40005 0 90)
			(size 0 0)
			(layers "F.Cu" "F.Mask" "F.Paste")
			(net "SSD0_CLK_EN_N")
		)
		(pad "2" smd circle
			(at 0.40005 0 90)
			(size 0 0)
			(layers "F.Cu" "F.Mask" "F.Paste")
			(net "SSD0_CLK_EN_R_N")
		)
	)
	(footprint ""
		(layer "F.Cu")
		(at 446.855596 -254.5969 -90)
		(property "Reference" "C4408"
			(at 0 0 270)
			(layer "F.SilkS")
			(hide yes)
			(effects
				(font
					(size 1.27 1.27)
				)
			)
		)
		(property "Value" ""
			(at 0 0 270)
			(layer "F.Fab")
			(effects
				(font
					(size 1.27 1.27)
				)
			)
		)
		(duplicate_pad_numbers_are_jumpers no)
		(fp_line
			(start -1.2954 0.5842)
			(end -1.2954 -0.5842)
			(stroke
				(width 0.1524)
				(type default)
			)
			(layer "F.SilkS")
		)
		(fp_line
			(start 1.2954 0.5842)
			(end -1.2954 0.5842)
			(stroke
				(width 0.1524)
				(type default)
			)
			(layer "F.SilkS")
		)
		(fp_line
			(start -1.2954 -0.5842)
			(end 1.2954 -0.5842)
			(stroke
				(width 0.1524)
				(type default)
			)
			(layer "F.SilkS")
		)
		(fp_line
			(start 1.2954 -0.5842)
			(end 1.2954 0.5842)
			(stroke
				(width 0.1524)
				(type default)
			)
			(layer "F.SilkS")
		)
		(fp_line
			(start -0.8636 0.4572)
			(end -0.8636 0.4064)
			(stroke
				(width 0.1)
				(type default)
			)
			(layer "F.Fab")
		)
		(fp_line
			(start 0.8636 0.4572)
			(end -0.8636 0.4572)
			(stroke
				(width 0.1)
				(type default)
			)
			(layer "F.Fab")
		)
		(fp_line
			(start -1.1938 0.4064)
			(end -1.1938 -0.4064)
			(stroke
				(width 0.1)
				(type default)
			)
			(layer "F.Fab")
		)
		(fp_line
			(start -0.8636 0.4064)
			(end -1.1938 0.4064)
			(stroke
				(width 0.1)
				(type default)
			)
			(layer "F.Fab")
		)
		(fp_line
			(start 0.8636 0.4064)
			(end 0.8636 0.4572)
			(stroke
				(width 0.1)
				(type default)
			)
			(layer "F.Fab")
		)
		(fp_line
			(start 1.1938 0.4064)
			(end 0.8636 0.4064)
			(stroke
				(width 0.1)
				(type default)
			)
			(layer "F.Fab")
		)
		(fp_line
			(start -1.1938 -0.4064)
			(end -0.8636 -0.4064)
			(stroke
				(width 0.1)
				(type default)
			)
			(layer "F.Fab")
		)
		(fp_line
			(start -0.8636 -0.4064)
			(end -0.8636 -0.4572)
			(stroke
				(width 0.1)
				(type default)
			)
			(layer "F.Fab")
		)
		(fp_line
			(start 0.8636 -0.4064)
			(end 1.1938 -0.4064)
			(stroke
				(width 0.1)
				(type default)
			)
			(layer "F.Fab")
		)
		(fp_line
			(start 1.1938 -0.4064)
			(end 1.1938 0.4064)
			(stroke
				(width 0.1)
				(type default)
			)
			(layer "F.Fab")
		)
		(fp_line
			(start -0.8636 -0.4572)
			(end 0.8636 -0.4572)
			(stroke
				(width 0.1)
				(type default)
			)
			(layer "F.Fab")
		)
		(fp_line
			(start 0.8636 -0.4572)
			(end 0.8636 -0.4064)
			(stroke
				(width 0.1)
				(type default)
			)
			(layer "F.Fab")
		)
		(pad "1" smd rect
			(at -0.7366 0 180)
			(size 0.7112 0.8128)
			(layers "F.Cu" "F.Mask" "F.Paste")
			(net "P1V25_SERDES_VDDPLL_PEX3_C6")
		)
		(pad "2" smd rect
			(at 0.7366 0 180)
			(size 0.7112 0.8128)
			(layers "F.Cu" "F.Mask" "F.Paste")
			(net "GND")
		)
	)
	(footprint ""
		(layer "F.Cu")
		(at 133.77672 -280.344118)
		(property "Reference" "PC106"
			(at 0 0 0)
			(layer "F.SilkS")
			(hide yes)
			(effects
				(font
					(size 1.27 1.27)
				)
			)
		)
		(property "Value" ""
			(at 0 0 0)
			(layer "F.Fab")
			(effects
				(font
					(size 1.27 1.27)
				)
			)
		)
		(duplicate_pad_numbers_are_jumpers no)
		(fp_line
			(start -0.7874 -0.4064)
			(end 0.7874 -0.4064)
			(stroke
				(width 0.1524)
				(type default)
			)
			(layer "F.SilkS")
		)
		(fp_line
			(start -0.7874 0.4064)
			(end -0.7874 -0.4064)
			(stroke
				(width 0.1524)
				(type default)
			)
			(layer "F.SilkS")
		)
		(fp_line
			(start 0.7874 -0.4064)
			(end 0.7874 0.4064)
			(stroke
				(width 0.1524)
				(type default)
			)
			(layer "F.SilkS")
		)
		(fp_line
			(start 0.7874 0.4064)
			(end -0.7874 0.4064)
			(stroke
				(width 0.1524)
				(type default)
			)
			(layer "F.SilkS")
		)
		(fp_line
			(start -0.67945 -0.305054)
			(end -0.12065 -0.305054)
			(stroke
				(width 0.1)
				(type default)
			)
			(layer "F.Fab")
		)
		(fp_line
			(start -0.67945 0.3048)
			(end -0.67945 -0.305054)
			(stroke
				(width 0.1)
				(type default)
			)
			(layer "F.Fab")
		)
		(fp_line
			(start -0.12065 -0.305054)
			(end -0.12065 -0.2794)
			(stroke
				(width 0.1)
				(type default)
			)
			(layer "F.Fab")
		)
		(fp_line
			(start -0.12065 -0.2794)
			(end 0.12065 -0.2794)
			(stroke
				(width 0.1)
				(type default)
			)
			(layer "F.Fab")
		)
		(fp_line
			(start -0.12065 0.2794)
			(end -0.12065 0.3048)
			(stroke
				(width 0.1)
				(type default)
			)
			(layer "F.Fab")
		)
		(fp_line
			(start -0.12065 0.3048)
			(end -0.67945 0.3048)
			(stroke
				(width 0.1)
				(type default)
			)
			(layer "F.Fab")
		)
		(fp_line
			(start 0.120396 0.2794)
			(end -0.12065 0.2794)
			(stroke
				(width 0.1)
				(type default)
			)
			(layer "F.Fab")
		)
		(fp_line
			(start 0.120396 0.3048)
			(end 0.120396 0.2794)
			(stroke
				(width 0.1)
				(type default)
			)
			(layer "F.Fab")
		)
		(fp_line
			(start 0.12065 -0.3048)
			(end 0.67945 -0.3048)
			(stroke
				(width 0.1)
				(type default)
			)
			(layer "F.Fab")
		)
		(fp_line
			(start 0.12065 -0.2794)
			(end 0.12065 -0.3048)
			(stroke
				(width 0.1)
				(type default)
			)
			(layer "F.Fab")
		)
		(fp_line
			(start 0.67945 -0.3048)
			(end 0.67945 0.3048)
			(stroke
				(width 0.1)
				(type default)
			)
			(layer "F.Fab")
		)
		(fp_line
			(start 0.67945 0.3048)
			(end 0.120396 0.3048)
			(stroke
				(width 0.1)
				(type default)
			)
			(layer "F.Fab")
		)
		(pad "1" smd circle
			(at -0.40005 0)
			(size 0 0)
			(layers "F.Cu" "F.Mask" "F.Paste")
			(net "P0V8_PEX0_VREF")
		)
		(pad "2" smd circle
			(at 0.40005 0)
			(size 0 0)
			(layers "F.Cu" "F.Mask" "F.Paste")
			(net "GND")
		)
	)
	(footprint ""
		(layer "F.Cu")
		(at 416.287966 -45.704252 90)
		(property "Reference" "R661"
			(at 0 0 90)
			(layer "F.SilkS")
			(hide yes)
			(effects
				(font
					(size 1.27 1.27)
				)
			)
		)
		(property "Value" ""
			(at 0 0 90)
			(layer "F.Fab")
			(effects
				(font
					(size 1.27 1.27)
				)
			)
		)
		(duplicate_pad_numbers_are_jumpers no)
		(fp_line
			(start 3.937508 -1.8796)
			(end -3.937508 -1.8796)
			(stroke
				(width 0.1524)
				(type default)
			)
			(layer "F.SilkS")
		)
		(fp_line
			(start -3.937508 -1.8796)
			(end -3.937508 1.8796)
			(stroke
				(width 0.1524)
				(type default)
			)
			(layer "F.SilkS")
		)
		(fp_line
			(start 3.937508 1.8796)
			(end 3.937508 -1.8796)
			(stroke
				(width 0.1524)
				(type default)
			)
			(layer "F.SilkS")
		)
		(fp_line
			(start -3.937508 1.8796)
			(end 3.937508 1.8796)
			(stroke
				(width 0.1524)
				(type default)
			)
			(layer "F.SilkS")
		)
		(fp_line
			(start 3.275076 -1.674876)
			(end -3.275076 -1.674876)
			(stroke
				(width 0.1)
				(type default)
			)
			(layer "F.Fab")
		)
		(fp_line
			(start -3.275076 -1.674876)
			(end -3.275076 1.674876)
			(stroke
				(width 0.1)
				(type default)
			)
			(layer "F.Fab")
		)
		(fp_line
			(start 3.275076 1.674876)
			(end 3.275076 -1.674876)
			(stroke
				(width 0.1)
				(type default)
			)
			(layer "F.Fab")
		)
		(fp_line
			(start -3.275076 1.674876)
			(end 3.275076 1.674876)
			(stroke
				(width 0.1)
				(type default)
			)
			(layer "F.Fab")
		)
		(pad "1" smd rect
			(at -2.350008 0 90)
			(size 2.921 3.5052)
			(layers "F.Cu" "F.Mask" "F.Paste")
			(net "P12V_SSD14")
		)
		(pad "2" smd rect
			(at 2.350008 0 90)
			(size 2.921 3.5052)
			(layers "F.Cu" "F.Mask" "F.Paste")
			(net "P12V_SSD14_R")
		)
	)
)
